# S9S_MB_2U (Grand Teton) — schematic netlist excerpt (pin names and nets, part order shuffled) for the footprints in the layout excerpt that follows; sources: Cadence DE-HDL packaged netlist, KiCad conversion of 03242023_DA0F0TMBIJ0_F0T_Motherboard_J_brd_V01_OCP.brd

U97  NX3L2267GM  IC  pkg XQFN10  page 239
  \1y0\  = JTAG_BMC_PLD_TMS
  \1y1\  = JTAG_BMC_DBP_TMS
  \2y0\  = JTAG_BMC_PLD_TCK
  \2y1\  = JTAG_BMC_DBP_TCK
  GND  = GND
  \2z\  = JTAG_BMC_SW_TCK
  \2s\  = FM_JTAG_BMC_MUX_SEL
  \1s\  = FM_JTAG_BMC_MUX_SEL
  \1z\  = JTAG_BMC_SW_TMS
  VCC  = P3V3_AUX

(kicad_pcb
	(version 20260206)
	(generator "pcbnew")
	(generator_version "10.0")
	(general
		(thickness 1.6)
		(legacy_teardrops no)
	)
	(paper "A4")
	(title_block
		(title "03242023_DA0F0TMBIJ0_F0T_Motherboard_J_brd_V01_OCP.brd")
		(comment 1 "Grand Teton / footprints 4009-4009 of 6105")
	)
	(layers
		(0 "F.Cu" signal "TOP")
		(4 "In1.Cu" signal "GND")
		(6 "In2.Cu" signal "IN1")
		(8 "In3.Cu" signal "GND1")
		(10 "In4.Cu" signal "IN2")
		(12 "In5.Cu" signal "GND2")
		(14 "In6.Cu" signal "IN3")
		(16 "In7.Cu" signal "GND3")
		(18 "In8.Cu" signal "VCC")
		(20 "In9.Cu" signal "VCC1")
		(22 "In10.Cu" signal "GND4")
		(24 "In11.Cu" signal "IN4")
		(26 "In12.Cu" signal "GND5")
		(28 "In13.Cu" signal "IN5")
		(30 "In14.Cu" signal "GND6")
		(32 "In15.Cu" signal "IN6")
		(34 "In16.Cu" signal "GND7")
		(2 "B.Cu" signal "BOTTOM")
		(9 "F.Adhes" user "F.Adhesive")
		(11 "B.Adhes" user "B.Adhesive")
		(13 "F.Paste" user "Package Geometry/Pastemask Top")
		(15 "B.Paste" user "Package Geometry/Pastemask Bottom")
		(5 "F.SilkS" user "Ref Des/Silkscreen Top")
		(7 "B.SilkS" user "Ref Des/Silkscreen Bottom")
		(1 "F.Mask" user "Board Geometry/Soldermask Top")
		(3 "B.Mask" user "Board Geometry/Soldermask Bottom")
		(17 "Dwgs.User" user "User.Drawings")
		(19 "Cmts.User" user "User.Comments")
		(21 "Eco1.User" user "User.Eco1")
		(23 "Eco2.User" user "User.Eco2")
		(25 "Edge.Cuts" user "Board Geometry/Outline")
		(27 "Margin" user)
		(31 "F.CrtYd" user "Package Geometry/Place Bound Top")
		(29 "B.CrtYd" user "Package Geometry/Place Bound Bottom")
		(35 "F.Fab" user "Ref Des/Assembly Top")
		(33 "B.Fab" user "Ref Des/Assembly Bottom")
	)
	(footprint ""
		(layer "F.Cu")
		(at 118.804944 -77.748892 180)
		(property "Reference" "U97"
			(at 0.831088 2.72542 0)
			(unlocked yes)
			(layer "F.SilkS")
			(effects
				(font
					(size 0.7874 0.5842)
					(thickness 0.1524)
				)
				(justify left)
			)
		)
		(property "Value" ""
			(at 0 0 180)
			(layer "F.Fab")
			(effects
				(font
					(size 1.27 1.27)
				)
			)
		)
		(duplicate_pad_numbers_are_jumpers no)
		(fp_line
			(start 0.824992 1.050036)
			(end 0.254 1.050036)
			(stroke
				(width 0.1524)
				(type default)
			)
			(layer "F.SilkS")
		)
		(fp_line
			(start 0.824992 1.00584)
			(end 0.824992 1.050036)
			(stroke
				(width 0.1524)
				(type default)
			)
			(layer "F.SilkS")
		)
		(fp_line
			(start 0.824992 -1.050036)
			(end 0.824992 -1.00584)
			(stroke
				(width 0.1524)
				(type default)
			)
			(layer "F.SilkS")
		)
		(fp_line
			(start 0.254 -1.050036)
			(end 0.824992 -1.050036)
			(stroke
				(width 0.1524)
				(type default)
			)
			(layer "F.SilkS")
		)
		(fp_line
			(start -0.254 1.050036)
			(end -0.824992 1.050036)
			(stroke
				(width 0.1524)
				(type default)
			)
			(layer "F.SilkS")
		)
		(fp_line
			(start -0.824992 1.050036)
			(end -0.824992 1.00584)
			(stroke
				(width 0.1524)
				(type default)
			)
			(layer "F.SilkS")
		)
		(fp_line
			(start -0.824992 -1.01854)
			(end -0.824992 -1.050036)
			(stroke
				(width 0.1524)
				(type default)
			)
			(layer "F.SilkS")
		)
		(fp_line
			(start -0.824992 -1.050036)
			(end -0.254 -1.050036)
			(stroke
				(width 0.1524)
				(type default)
			)
			(layer "F.SilkS")
		)
		(fp_poly
			(pts
				(xy -2.027428 -0.399034) (xy -2.027428 -1.10109) (xy -1.325372 -0.750062)
			)
			(stroke
				(width 0)
				(type default)
			)
			(fill yes)
			(layer "F.SilkS")
		)
		(fp_line
			(start 0.824992 1.050036)
			(end -0.824992 1.050036)
			(stroke
				(width 0.1)
				(type default)
			)
			(layer "F.Fab")
		)
		(fp_line
			(start 0.824992 -1.050036)
			(end 0.824992 1.050036)
			(stroke
				(width 0.1)
				(type default)
			)
			(layer "F.Fab")
		)
		(fp_line
			(start -0.824992 1.050036)
			(end -0.824992 -1.050036)
			(stroke
				(width 0.1)
				(type default)
			)
			(layer "F.Fab")
		)
		(fp_line
			(start -0.824992 -1.050036)
			(end 0.824992 -1.050036)
			(stroke
				(width 0.1)
				(type default)
			)
			(layer "F.Fab")
		)
		(fp_poly
			(pts
				(xy -1.325372 -0.750062) (xy -2.027428 -0.399034) (xy -2.027428 -1.10109)
			)
			(stroke
				(width 0)
				(type default)
			)
			(fill yes)
			(layer "F.Fab")
		)
		(pad "1" smd rect
			(at -0.741172 -0.750062 270)
			(size 0.2794 0.8128)
			(layers "F.Cu" "F.Mask" "F.Paste")
			(net "JTAG_BMC_PLD_TMS")
		)
		(pad "2" smd rect
			(at -0.741172 -0.249936 270)
			(size 0.254 0.8128)
			(layers "F.Cu" "F.Mask" "F.Paste")
			(net "JTAG_BMC_DBP_TMS")
		)
		(pad "3" smd rect
			(at -0.741172 0.249936 270)
			(size 0.254 0.8128)
			(layers "F.Cu" "F.Mask" "F.Paste")
			(net "JTAG_BMC_PLD_TCK")
		)
		(pad "4" smd rect
			(at -0.741172 0.750062 270)
			(size 0.254 0.8128)
			(layers "F.Cu" "F.Mask" "F.Paste")
			(net "JTAG_BMC_DBP_TCK")
		)
		(pad "5" smd rect
			(at 0 0.94996 180)
			(size 0.254 0.8128)
			(layers "F.Cu" "F.Mask" "F.Paste")
			(net "GND")
		)
		(pad "6" smd rect
			(at 0.741172 0.750062 270)
			(size 0.254 0.8128)
			(layers "F.Cu" "F.Mask" "F.Paste")
			(net "JTAG_BMC_SW_TCK")
		)
		(pad "7" smd rect
			(at 0.741172 0.249936 270)
			(size 0.254 0.8128)
			(layers "F.Cu" "F.Mask" "F.Paste")
			(net "FM_JTAG_BMC_MUX_SEL")
		)
		(pad "8" smd rect
			(at 0.741172 -0.249936 270)
			(size 0.254 0.8128)
			(layers "F.Cu" "F.Mask" "F.Paste")
			(net "FM_JTAG_BMC_MUX_SEL")
		)
		(pad "9" smd rect
			(at 0.741172 -0.750062 270)
			(size 0.254 0.8128)
			(layers "F.Cu" "F.Mask" "F.Paste")
			(net "JTAG_BMC_SW_TMS")
		)
		(pad "10" smd rect
			(at 0 -0.94996 180)
			(size 0.254 0.8128)
			(layers "F.Cu" "F.Mask" "F.Paste")
			(net "P3V3_AUX")
		)
		(zone
			(layer "F.Cu")
			(hatch none 0.5)
			(connect_pads
				(clearance 0)
			)
			(min_thickness 0.25)
			(keepout
				(tracks not_allowed)
				(vias allowed)
				(pads allowed)
				(copperpour not_allowed)
				(footprints allowed)
			)
			(placement
				(enabled no)
				(sheetname "")
			)
			(fill
				(thermal_gap 0.5)
				(thermal_bridge_width 0.5)
				(island_removal_mode 0)
			)
			(polygon
				(pts
					(xy 119.630444 -76.809092) (xy 119.630444 -76.694792) (xy 119.084344 -76.694792) (xy 119.084344 -76.809092)
				)
			)
		)
	)
)
